# BASEBOARD_FAB2 (Tioga Pass) — schematic netlist excerpt (pin names and nets, part order shuffled) for the footprints in the layout excerpt that follows; sources: Cadence DE-HDL packaged netlist, KiCad conversion of Wiwynn_Tioga_Pass_MB.brd

R4D58  RES  1.00K 1% CHIP  pkg 0402  page 201 : A = P3V3_STBY ; B = VR_VRRDY_PVCCIN_CPU0
R2T29  RES  2.21K 1% CHIP  pkg 0402  page 157 : A = P3V3_STBY ; B = IRQ_OOB_MGMT_RISER_ALERT_N
R1E12  RES  4.75K 1% CHIP  pkg 0402  page 161 : A = P5V_STBY ; B = FAN_PWM_OUT_SYS0_R

(kicad_pcb
	(version 20260206)
	(generator "pcbnew")
	(generator_version "10.0")
	(general
		(thickness 1.6)
		(legacy_teardrops no)
	)
	(paper "A4")
	(title_block
		(title "Wiwynn_Tioga_Pass_MB.brd")
		(comment 1 "Tioga Pass / footprints 412-414 of 4770")
	)
	(layers
		(0 "F.Cu" signal "TOP")
		(4 "In1.Cu" signal "L2GND")
		(6 "In2.Cu" signal "L3")
		(8 "In3.Cu" signal "L4GND")
		(10 "In4.Cu" signal "L5")
		(12 "In5.Cu" signal "L6GND")
		(14 "In6.Cu" signal "L7VCC")
		(16 "In7.Cu" signal "L8VCC")
		(18 "In8.Cu" signal "L9GND")
		(20 "In9.Cu" signal "L10")
		(22 "In10.Cu" signal "L11GND")
		(24 "In11.Cu" signal "L12")
		(26 "In12.Cu" signal "L13GND")
		(2 "B.Cu" signal "BOTTOM")
		(9 "F.Adhes" user "F.Adhesive")
		(11 "B.Adhes" user "B.Adhesive")
		(13 "F.Paste" user "Package Geometry/Pastemask Top")
		(15 "B.Paste" user "Package Geometry/Pastemask Bottom")
		(5 "F.SilkS" user "Ref Des/Silkscreen Top")
		(7 "B.SilkS" user "Ref Des/Silkscreen Bottom")
		(1 "F.Mask" user "Board Geometry/Soldermask Top")
		(3 "B.Mask" user "Board Geometry/Soldermask Bottom")
		(17 "Dwgs.User" user "User.Drawings")
		(19 "Cmts.User" user "User.Comments")
		(21 "Eco1.User" user "User.Eco1")
		(23 "Eco2.User" user "User.Eco2")
		(25 "Edge.Cuts" user "Board Geometry/Outline")
		(27 "Margin" user)
		(31 "F.CrtYd" user "Package Geometry/Place Bound Top")
		(29 "B.CrtYd" user "Package Geometry/Place Bound Bottom")
		(35 "F.Fab" user "Ref Des/Assembly Top")
		(33 "B.Fab" user "Ref Des/Assembly Bottom")
	)
	(footprint ""
		(layer "F.Cu")
		(at 24.1554 -41.2242 -90)
		(property "Reference" "R1E12"
			(at 0 0 270)
			(layer "F.SilkS")
			(hide yes)
			(effects
				(font
					(size 1.27 1.27)
				)
			)
		)
		(property "Value" ""
			(at 0 0 270)
			(layer "F.Fab")
			(effects
				(font
					(size 1.27 1.27)
				)
			)
		)
		(duplicate_pad_numbers_are_jumpers no)
		(fp_rect
			(start 0.2794 0.9906)
			(end -0.2794 -0.1016)
			(stroke
				(width 0)
				(type default)
			)
			(fill no)
			(layer "F.CrtYd")
		)
		(fp_line
			(start -0.2794 0.9906)
			(end 0.2794 0.9906)
			(stroke
				(width 0.1)
				(type default)
			)
			(layer "F.Fab")
		)
		(fp_line
			(start 0.2794 0.9906)
			(end 0.2794 -0.1016)
			(stroke
				(width 0.1)
				(type default)
			)
			(layer "F.Fab")
		)
		(fp_line
			(start -0.2794 -0.1016)
			(end -0.2794 0.9906)
			(stroke
				(width 0.1)
				(type default)
			)
			(layer "F.Fab")
		)
		(fp_line
			(start 0.2794 -0.1016)
			(end -0.2794 -0.1016)
			(stroke
				(width 0.1)
				(type default)
			)
			(layer "F.Fab")
		)
		(pad "1" smd rect
			(at 0 0 270)
			(size 0.508 0.508)
			(layers "F.Cu" "F.Mask" "F.Paste")
			(net "P5V_STBY")
		)
		(pad "2" smd rect
			(at 0 0.889 270)
			(size 0.508 0.508)
			(layers "F.Cu" "F.Mask" "F.Paste")
			(net "FAN_PWM_OUT_SYS0_R")
		)
		(zone
			(layer "F.Cu")
			(hatch none 0.5)
			(connect_pads
				(clearance 0)
			)
			(min_thickness 0.25)
			(keepout
				(tracks not_allowed)
				(vias allowed)
				(pads allowed)
				(copperpour not_allowed)
				(footprints allowed)
			)
			(placement
				(enabled no)
				(sheetname "")
			)
			(fill
				(thermal_gap 0.5)
				(thermal_bridge_width 0.5)
				(island_removal_mode 0)
			)
			(polygon
				(pts
					(xy 23.5204 -40.9702) (xy 23.9014 -40.9702) (xy 23.9014 -41.4782) (xy 23.5204 -41.4782)
				)
			)
		)
		(zone
			(layer "F.Cu")
			(hatch none 0.5)
			(connect_pads
				(clearance 0)
			)
			(min_thickness 0.25)
			(keepout
				(tracks allowed)
				(vias not_allowed)
				(pads allowed)
				(copperpour not_allowed)
				(footprints allowed)
			)
			(placement
				(enabled no)
				(sheetname "")
			)
			(fill
				(thermal_gap 0.5)
				(thermal_bridge_width 0.5)
				(island_removal_mode 0)
			)
			(polygon
				(pts
					(xy 23.5204 -40.9702) (xy 23.9014 -40.9702) (xy 23.9014 -41.4782) (xy 23.5204 -41.4782)
				)
			)
		)
	)
	(footprint ""
		(layer "F.Cu")
		(at 178.689 -66.548 90)
		(property "Reference" "R4D58"
			(at 0 0 90)
			(layer "F.SilkS")
			(hide yes)
			(effects
				(font
					(size 1.27 1.27)
				)
			)
		)
		(property "Value" ""
			(at 0 0 90)
			(layer "F.Fab")
			(effects
				(font
					(size 1.27 1.27)
				)
			)
		)
		(duplicate_pad_numbers_are_jumpers no)
		(fp_rect
			(start -0.2794 -0.1016)
			(end 0.2794 0.9906)
			(stroke
				(width 0)
				(type default)
			)
			(fill no)
			(layer "F.CrtYd")
		)
		(fp_line
			(start 0.2794 -0.1016)
			(end -0.2794 -0.1016)
			(stroke
				(width 0.1)
				(type default)
			)
			(layer "F.Fab")
		)
		(fp_line
			(start -0.2794 -0.1016)
			(end -0.2794 0.9906)
			(stroke
				(width 0.1)
				(type default)
			)
			(layer "F.Fab")
		)
		(fp_line
			(start 0.2794 0.9906)
			(end 0.2794 -0.1016)
			(stroke
				(width 0.1)
				(type default)
			)
			(layer "F.Fab")
		)
		(fp_line
			(start -0.2794 0.9906)
			(end 0.2794 0.9906)
			(stroke
				(width 0.1)
				(type default)
			)
			(layer "F.Fab")
		)
		(pad "1" smd rect
			(at 0 0 90)
			(size 0.508 0.508)
			(layers "F.Cu" "F.Mask" "F.Paste")
			(net "P3V3_STBY")
		)
		(pad "2" smd rect
			(at 0 0.889 90)
			(size 0.508 0.508)
			(layers "F.Cu" "F.Mask" "F.Paste")
			(net "VR_VRRDY_PVCCIN_CPU0")
		)
		(zone
			(layer "F.Cu")
			(hatch none 0.5)
			(connect_pads
				(clearance 0)
			)
			(min_thickness 0.25)
			(keepout
				(tracks not_allowed)
				(vias allowed)
				(pads allowed)
				(copperpour not_allowed)
				(footprints allowed)
			)
			(placement
				(enabled no)
				(sheetname "")
			)
			(fill
				(thermal_gap 0.5)
				(thermal_bridge_width 0.5)
				(island_removal_mode 0)
			)
			(polygon
				(pts
					(xy 178.943 -66.294) (xy 179.324 -66.294) (xy 179.324 -66.802) (xy 178.943 -66.802)
				)
			)
		)
		(zone
			(layer "F.Cu")
			(hatch none 0.5)
			(connect_pads
				(clearance 0)
			)
			(min_thickness 0.25)
			(keepout
				(tracks allowed)
				(vias not_allowed)
				(pads allowed)
				(copperpour not_allowed)
				(footprints allowed)
			)
			(placement
				(enabled no)
				(sheetname "")
			)
			(fill
				(thermal_gap 0.5)
				(thermal_bridge_width 0.5)
				(island_removal_mode 0)
			)
			(polygon
				(pts
					(xy 178.943 -66.294) (xy 179.324 -66.294) (xy 179.324 -66.802) (xy 178.943 -66.802)
				)
			)
		)
	)
	(footprint ""
		(layer "F.Cu")
		(at 413.3215 -112.649 -90)
		(property "Reference" "R2T29"
			(at 0 0 270)
			(layer "F.SilkS")
			(hide yes)
			(effects
				(font
					(size 1.27 1.27)
				)
			)
		)
		(property "Value" ""
			(at 0 0 270)
			(layer "F.Fab")
			(effects
				(font
					(size 1.27 1.27)
				)
			)
		)
		(duplicate_pad_numbers_are_jumpers no)
		(fp_poly
			(pts
				(xy -0.2794 -0.1016) (xy 0.2794 -0.1016) (xy 0.2794 0.9906) (xy -0.2794 0.9906)
			)
			(stroke
				(width 0)
				(type default)
			)
			(fill no)
			(layer "F.CrtYd")
		)
		(fp_line
			(start -0.2794 0.9906)
			(end 0.2794 0.9906)
			(stroke
				(width 0.1)
				(type default)
			)
			(layer "F.Fab")
		)
		(fp_line
			(start 0.2794 0.9906)
			(end 0.2794 -0.1016)
			(stroke
				(width 0.1)
				(type default)
			)
			(layer "F.Fab")
		)
		(fp_line
			(start -0.2794 -0.1016)
			(end -0.2794 0.9906)
			(stroke
				(width 0.1)
				(type default)
			)
			(layer "F.Fab")
		)
		(fp_line
			(start 0.2794 -0.1016)
			(end -0.2794 -0.1016)
			(stroke
				(width 0.1)
				(type default)
			)
			(layer "F.Fab")
		)
		(pad "1" smd rect
			(at 0 0 270)
			(size 0.508 0.508)
			(layers "F.Cu" "F.Mask" "F.Paste")
			(net "P3V3_STBY")
		)
		(pad "2" smd rect
			(at 0 0.889 270)
			(size 0.508 0.508)
			(layers "F.Cu" "F.Mask" "F.Paste")
			(net "IRQ_OOB_MGMT_RISER_ALERT_N")
		)
		(zone
			(layer "F.Cu")
			(hatch none 0.5)
			(connect_pads
				(clearance 0)
			)
			(min_thickness 0.25)
			(keepout
				(tracks not_allowed)
				(vias allowed)
				(pads allowed)
				(copperpour not_allowed)
				(footprints allowed)
			)
			(placement
				(enabled no)
				(sheetname "")
			)
			(fill
				(thermal_gap 0.5)
				(thermal_bridge_width 0.5)
				(island_removal_mode 0)
			)
			(polygon
				(pts
					(xy 412.6865 -112.903) (xy 412.6865 -112.395) (xy 413.0675 -112.395) (xy 413.0675 -112.903)
				)
			)
		)
		(zone
			(layer "F.Cu")
			(hatch none 0.5)
			(connect_pads
				(clearance 0)
			)
			(min_thickness 0.25)
			(keepout
				(tracks allowed)
				(vias not_allowed)
				(pads allowed)
				(copperpour not_allowed)
				(footprints allowed)
			)
			(placement
				(enabled no)
				(sheetname "")
			)
			(fill
				(thermal_gap 0.5)
				(thermal_bridge_width 0.5)
				(island_removal_mode 0)
			)
			(polygon
				(pts
					(xy 413.0675 -112.903) (xy 413.0675 -112.395) (xy 412.6865 -112.395) (xy 412.6865 -112.903)
				)
			)
		)
	)
)
